# T6G (Grand Teton) — schematic netlist excerpt (pin names and nets, part order shuffled) for the footprints in the layout excerpt that follows; sources: Cadence DE-HDL packaged netlist, KiCad conversion of 04192023_DAF0TMB3IC0_F0TG_MB_C_brd_V02_OCP.brd

PC6631  Q_CAPP  390UF 2.5V 20% ALUM  pkg SMLF  page 365 : A = P0V9_CPU1_RT_2D ; B = GND
PC454  Q_CAPP  270UF 16V 20% OSCON  pkg SMLF  page 222 : A = SW_P12V_AUX_PVDDIO_P1_FLT ; B = GND
PC15  Q_CAP  0.1UF 25V 10% X7R  pkg 0402  page 200 : A = PVDDCR_CPU1_P0_VCCS ; B = GND

(kicad_pcb
	(version 20260206)
	(generator "pcbnew")
	(generator_version "10.0")
	(general
		(thickness 1.6)
		(legacy_teardrops no)
	)
	(paper "A4")
	(title_block
		(title "04192023_DAF0TMB3IC0_F0TG_MB_C_brd_V02_OCP.brd")
		(comment 1 "Grand Teton / footprints 841-843 of 8354")
	)
	(layers
		(0 "F.Cu" signal "TOP")
		(4 "In1.Cu" signal "GND")
		(6 "In2.Cu" signal "IN1")
		(8 "In3.Cu" signal "GND1")
		(10 "In4.Cu" signal "IN2")
		(12 "In5.Cu" signal "GND2")
		(14 "In6.Cu" signal "IN3")
		(16 "In7.Cu" signal "GND3")
		(18 "In8.Cu" signal "VCC")
		(20 "In9.Cu" signal "VCC1")
		(22 "In10.Cu" signal "GND4")
		(24 "In11.Cu" signal "IN4")
		(26 "In12.Cu" signal "GND5")
		(28 "In13.Cu" signal "IN5")
		(30 "In14.Cu" signal "GND6")
		(32 "In15.Cu" signal "IN6")
		(34 "In16.Cu" signal "GND7")
		(2 "B.Cu" signal "BOTTOM")
		(9 "F.Adhes" user "F.Adhesive")
		(11 "B.Adhes" user "B.Adhesive")
		(13 "F.Paste" user "Package Geometry/Pastemask Top")
		(15 "B.Paste" user "Package Geometry/Pastemask Bottom")
		(5 "F.SilkS" user "Ref Des/Silkscreen Top")
		(7 "B.SilkS" user "Ref Des/Silkscreen Bottom")
		(1 "F.Mask" user "Board Geometry/Soldermask Top")
		(3 "B.Mask" user "Board Geometry/Soldermask Bottom")
		(17 "Dwgs.User" user "User.Drawings")
		(19 "Cmts.User" user "User.Comments")
		(21 "Eco1.User" user "User.Eco1")
		(23 "Eco2.User" user "User.Eco2")
		(25 "Edge.Cuts" user "Board Geometry/Outline")
		(27 "Margin" user)
		(31 "F.CrtYd" user "Package Geometry/Place Bound Top")
		(29 "B.CrtYd" user "Package Geometry/Place Bound Bottom")
		(35 "F.Fab" user "Ref Des/Assembly Top")
		(33 "B.Fab" user "Ref Des/Assembly Bottom")
	)
	(footprint ""
		(layer "F.Cu")
		(at 315.214 -366.395 90)
		(property "Reference" "PC15"
			(at 0 0 90)
			(layer "F.SilkS")
			(hide yes)
			(effects
				(font
					(size 1.27 1.27)
				)
			)
		)
		(property "Value" ""
			(at 0 0 90)
			(layer "F.Fab")
			(effects
				(font
					(size 1.27 1.27)
				)
			)
		)
		(duplicate_pad_numbers_are_jumpers no)
		(fp_line
			(start 0.7874 -0.4064)
			(end 0.7874 0.4064)
			(stroke
				(width 0.1524)
				(type default)
			)
			(layer "F.SilkS")
		)
		(fp_line
			(start -0.7874 -0.4064)
			(end 0.7874 -0.4064)
			(stroke
				(width 0.1524)
				(type default)
			)
			(layer "F.SilkS")
		)
		(fp_line
			(start 0.7874 0.4064)
			(end -0.7874 0.4064)
			(stroke
				(width 0.1524)
				(type default)
			)
			(layer "F.SilkS")
		)
		(fp_line
			(start -0.7874 0.4064)
			(end -0.7874 -0.4064)
			(stroke
				(width 0.1524)
				(type default)
			)
			(layer "F.SilkS")
		)
		(fp_line
			(start -0.12065 -0.305054)
			(end -0.12065 -0.2794)
			(stroke
				(width 0.1)
				(type default)
			)
			(layer "F.Fab")
		)
		(fp_line
			(start -0.67945 -0.305054)
			(end -0.12065 -0.305054)
			(stroke
				(width 0.1)
				(type default)
			)
			(layer "F.Fab")
		)
		(fp_line
			(start 0.67945 -0.3048)
			(end 0.67945 0.3048)
			(stroke
				(width 0.1)
				(type default)
			)
			(layer "F.Fab")
		)
		(fp_line
			(start 0.12065 -0.3048)
			(end 0.67945 -0.3048)
			(stroke
				(width 0.1)
				(type default)
			)
			(layer "F.Fab")
		)
		(fp_line
			(start 0.12065 -0.2794)
			(end 0.12065 -0.3048)
			(stroke
				(width 0.1)
				(type default)
			)
			(layer "F.Fab")
		)
		(fp_line
			(start -0.12065 -0.2794)
			(end 0.12065 -0.2794)
			(stroke
				(width 0.1)
				(type default)
			)
			(layer "F.Fab")
		)
		(fp_line
			(start 0.120396 0.2794)
			(end -0.12065 0.2794)
			(stroke
				(width 0.1)
				(type default)
			)
			(layer "F.Fab")
		)
		(fp_line
			(start -0.12065 0.2794)
			(end -0.12065 0.3048)
			(stroke
				(width 0.1)
				(type default)
			)
			(layer "F.Fab")
		)
		(fp_line
			(start 0.67945 0.3048)
			(end 0.120396 0.3048)
			(stroke
				(width 0.1)
				(type default)
			)
			(layer "F.Fab")
		)
		(fp_line
			(start 0.120396 0.3048)
			(end 0.120396 0.2794)
			(stroke
				(width 0.1)
				(type default)
			)
			(layer "F.Fab")
		)
		(fp_line
			(start -0.12065 0.3048)
			(end -0.67945 0.3048)
			(stroke
				(width 0.1)
				(type default)
			)
			(layer "F.Fab")
		)
		(fp_line
			(start -0.67945 0.3048)
			(end -0.67945 -0.305054)
			(stroke
				(width 0.1)
				(type default)
			)
			(layer "F.Fab")
		)
		(pad "1" smd circle
			(at -0.40005 0 90)
			(size 0 0)
			(layers "F.Cu" "F.Mask" "F.Paste")
			(net "PVDDCR_CPU1_P0_VCCS")
		)
		(pad "2" smd circle
			(at 0.40005 0 90)
			(size 0 0)
			(layers "F.Cu" "F.Mask" "F.Paste")
			(net "GND")
		)
	)
	(footprint ""
		(layer "F.Cu")
		(at 42.690034 -361.212892 90)
		(property "Reference" "PC454"
			(at 5.155438 -0.780034 0)
			(unlocked yes)
			(layer "F.SilkS")
			(effects
				(font
					(size 0.7874 0.5842)
					(thickness 0.1524)
				)
				(justify left)
			)
		)
		(property "Value" ""
			(at 0 0 90)
			(layer "F.Fab")
			(effects
				(font
					(size 1.27 1.27)
				)
			)
		)
		(duplicate_pad_numbers_are_jumpers no)
		(fp_line
			(start 3.400044 -3.400044)
			(end -2.146046 -3.400044)
			(stroke
				(width 0.1524)
				(type default)
			)
			(layer "F.SilkS")
		)
		(fp_line
			(start -2.146046 -3.400044)
			(end -3.400044 -2.146046)
			(stroke
				(width 0.1524)
				(type default)
			)
			(layer "F.SilkS")
		)
		(fp_line
			(start -3.400044 -2.146046)
			(end -3.400044 -0.9398)
			(stroke
				(width 0.1524)
				(type default)
			)
			(layer "F.SilkS")
		)
		(fp_line
			(start 3.400044 -0.9398)
			(end 3.400044 -3.400044)
			(stroke
				(width 0.1524)
				(type default)
			)
			(layer "F.SilkS")
		)
		(fp_line
			(start 3.400044 0.9398)
			(end 3.400044 3.400044)
			(stroke
				(width 0.1524)
				(type default)
			)
			(layer "F.SilkS")
		)
		(fp_line
			(start -3.400044 2.146046)
			(end -3.400044 0.9398)
			(stroke
				(width 0.1524)
				(type default)
			)
			(layer "F.SilkS")
		)
		(fp_line
			(start 3.400044 3.400044)
			(end -2.146046 3.400044)
			(stroke
				(width 0.1524)
				(type default)
			)
			(layer "F.SilkS")
		)
		(fp_line
			(start -2.146046 3.400044)
			(end -3.400044 2.146046)
			(stroke
				(width 0.1524)
				(type default)
			)
			(layer "F.SilkS")
		)
		(fp_line
			(start 3.400044 -3.400044)
			(end -3.400044 -3.400044)
			(stroke
				(width 0.1)
				(type default)
			)
			(layer "F.Fab")
		)
		(fp_line
			(start -3.400044 -3.400044)
			(end -3.400044 3.400044)
			(stroke
				(width 0.1)
				(type default)
			)
			(layer "F.Fab")
		)
		(fp_line
			(start 3.400044 3.400044)
			(end 3.400044 -3.400044)
			(stroke
				(width 0.1)
				(type default)
			)
			(layer "F.Fab")
		)
		(fp_line
			(start -3.400044 3.400044)
			(end 3.400044 3.400044)
			(stroke
				(width 0.1)
				(type default)
			)
			(layer "F.Fab")
		)
		(pad "1" smd rect
			(at -2.70002 0)
			(size 1.6002 3.5052)
			(layers "F.Cu" "F.Mask" "F.Paste")
			(net "SW_P12V_AUX_PVDDIO_P1_FLT")
		)
		(pad "2" smd rect
			(at 2.70002 0)
			(size 1.6002 3.5052)
			(layers "F.Cu" "F.Mask" "F.Paste")
			(net "GND")
		)
	)
	(footprint ""
		(layer "F.Cu")
		(at 24.961088 -373.44985 -90)
		(property "Reference" "PC6631"
			(at 4.54152 2.228088 0)
			(unlocked yes)
			(layer "F.SilkS")
			(effects
				(font
					(size 0.7874 0.5842)
					(thickness 0.1524)
				)
				(justify left)
			)
		)
		(property "Value" ""
			(at 0 0 270)
			(layer "F.Fab")
			(effects
				(font
					(size 1.27 1.27)
				)
			)
		)
		(duplicate_pad_numbers_are_jumpers no)
		(fp_line
			(start -1.988058 2.750058)
			(end 2.750058 2.750058)
			(stroke
				(width 0.1524)
				(type default)
			)
			(layer "F.SilkS")
		)
		(fp_line
			(start 2.750058 2.750058)
			(end 2.750058 0.9398)
			(stroke
				(width 0.1524)
				(type default)
			)
			(layer "F.SilkS")
		)
		(fp_line
			(start -2.750058 1.988058)
			(end -1.988058 2.750058)
			(stroke
				(width 0.1524)
				(type default)
			)
			(layer "F.SilkS")
		)
		(fp_line
			(start -2.750058 0.9398)
			(end -2.750058 1.988058)
			(stroke
				(width 0.1524)
				(type default)
			)
			(layer "F.SilkS")
		)
		(fp_line
			(start 2.750058 -0.9398)
			(end 2.750058 -2.750058)
			(stroke
				(width 0.1524)
				(type default)
			)
			(layer "F.SilkS")
		)
		(fp_line
			(start -2.750058 -1.988058)
			(end -2.750058 -0.9398)
			(stroke
				(width 0.1524)
				(type default)
			)
			(layer "F.SilkS")
		)
		(fp_line
			(start -1.988058 -2.750058)
			(end -2.750058 -1.988058)
			(stroke
				(width 0.1524)
				(type default)
			)
			(layer "F.SilkS")
		)
		(fp_line
			(start 2.750058 -2.750058)
			(end -1.988058 -2.750058)
			(stroke
				(width 0.1524)
				(type default)
			)
			(layer "F.SilkS")
		)
		(fp_line
			(start -2.750058 2.750058)
			(end 2.750058 2.750058)
			(stroke
				(width 0.1)
				(type default)
			)
			(layer "F.Fab")
		)
		(fp_line
			(start 2.750058 2.750058)
			(end 2.750058 -2.750058)
			(stroke
				(width 0.1)
				(type default)
			)
			(layer "F.Fab")
		)
		(fp_line
			(start -2.750058 -2.750058)
			(end -2.750058 2.750058)
			(stroke
				(width 0.1)
				(type default)
			)
			(layer "F.Fab")
		)
		(fp_line
			(start 2.750058 -2.750058)
			(end -2.750058 -2.750058)
			(stroke
				(width 0.1)
				(type default)
			)
			(layer "F.Fab")
		)
		(pad "1" smd rect
			(at -2.199894 0)
			(size 1.6002 3.0226)
			(layers "F.Cu" "F.Mask" "F.Paste")
			(net "P0V9_CPU1_RT_2D")
		)
		(pad "2" smd rect
			(at 2.199894 0)
			(size 1.6002 3.0226)
			(layers "F.Cu" "F.Mask" "F.Paste")
			(net "GND")
		)
	)
)
